(kicad_pcb
	(version 20241229)
	(generator "pcbnew")
	(generator_version "9.0")
	(general
		(thickness 1.294)
		(legacy_teardrops no)
	)
	(paper "A3")
	(title_block
		(title "Kintex 410T devboard")
		(date "2024-04-03")
		(rev "1.1.2")
		(comment 9 "footprints 562-566 of 975")
	)
	(layers
		(0 "F.Cu" mixed)
		(4 "In1.Cu" power)
		(6 "In2.Cu" power)
		(8 "In3.Cu" mixed)
		(10 "In4.Cu" power)
		(12 "In5.Cu" mixed)
		(14 "In6.Cu" power)
		(16 "In7.Cu" mixed)
		(18 "In8.Cu" power)
		(2 "B.Cu" mixed)
		(9 "F.Adhes" user "F.Adhesive")
		(11 "B.Adhes" user "B.Adhesive")
		(13 "F.Paste" user)
		(15 "B.Paste" user)
		(5 "F.SilkS" user "F.Silkscreen")
		(7 "B.SilkS" user "B.Silkscreen")
		(1 "F.Mask" user)
		(3 "B.Mask" user)
		(17 "Dwgs.User" user "User.Drawings")
		(19 "Cmts.User" user "User.Comments")
		(21 "Eco1.User" user "User.Eco1")
		(23 "Eco2.User" user "User.Eco2")
		(25 "Edge.Cuts" user)
		(27 "Margin" user)
		(31 "F.CrtYd" user "F.Courtyard")
		(29 "B.CrtYd" user "B.Courtyard")
		(35 "F.Fab" user)
		(33 "B.Fab" user)
	)
	(footprint "antmicro-footprints:R_Array_4x0201_Panasonic_EXB18V"
		(layer "B.Cu")
		(at 167.799999 146.199999 180)
		(property "Reference" "R17"
			(at 6.199999 -6.125001 0)
			(layer "B.SilkS")
			(effects
				(font
					(size 0.7 0.7)
					(thickness 0.15)
				)
				(justify right bottom mirror)
			)
		)
		(property "Value" "4x39R_0201_array"
			(at -1.1 -1.8 0)
			(layer "B.Fab")
			(effects
				(font
					(size 0.7 0.7)
					(thickness 0.15)
				)
				(justify left bottom mirror)
			)
		)
		(property "Description" "Fixed Network Resistor, 39 ohm, Isolated, 4 Resistors, 0502 [1406 Metric], Flat, ± 5%"
			(at 0 0 180)
			(layer "F.Fab")
			(hide yes)
			(effects
				(font
					(size 1.27 1.27)
					(thickness 0.15)
				)
			)
		)
		(property "Author" "Antmicro"
			(at 335.599998 292.399998 0)
			(layer "B.Fab")
			(hide yes)
			(effects
				(font
					(size 1 1)
					(thickness 0.15)
				)
				(justify mirror)
			)
		)
		(property "License" "Apache-2.0"
			(at 335.599998 292.399998 0)
			(layer "B.Fab")
			(hide yes)
			(effects
				(font
					(size 1 1)
					(thickness 0.15)
				)
				(justify mirror)
			)
		)
		(property "MPN" "EXB-18V390JX"
			(at 335.599998 292.399998 0)
			(layer "B.Fab")
			(hide yes)
			(effects
				(font
					(size 1 1)
					(thickness 0.15)
				)
				(justify mirror)
			)
		)
		(property "Manufacturer" "Panasonic"
			(at 335.599998 292.399998 0)
			(layer "B.Fab")
			(hide yes)
			(effects
				(font
					(size 1 1)
					(thickness 0.15)
				)
				(justify mirror)
			)
		)
		(property "Val" "4x39R_0201"
			(at 335.599998 292.399998 0)
			(layer "B.Fab")
			(hide yes)
			(effects
				(font
					(size 1 1)
					(thickness 0.15)
				)
				(justify mirror)
			)
		)
		(sheetname "DRAM + SRAM")
		(sheetfile "ram.kicad_sch")
		(attr smd)
		(fp_line
			(start 0.8 0.45)
			(end 0.8 -0.45)
			(stroke
				(width 0.12)
				(type solid)
			)
			(layer "B.SilkS")
		)
		(fp_line
			(start -0.8 0.45)
			(end -0.8 -0.45)
			(stroke
				(width 0.12)
				(type solid)
			)
			(layer "B.SilkS")
		)
		(fp_rect
			(start -0.898 0.66)
			(end 0.898 -0.65)
			(stroke
				(width 0.05)
				(type solid)
			)
			(fill no)
			(layer "B.CrtYd")
		)
		(pad "1" smd roundrect
			(at -0.6 -0.298 180)
			(size 0.2 0.4)
			(layers "B.Cu" "B.Mask" "B.Paste")
			(roundrect_rratio 0.25)
			(net 559 "/DRAM + SRAM/DDR.~{CAS}")
			(pinfunction "R1.1")
			(pintype "passive")
		)
		(pad "2" smd roundrect
			(at -0.202 -0.298 180)
			(size 0.2 0.4)
			(layers "B.Cu" "B.Mask" "B.Paste")
			(roundrect_rratio 0.25)
			(net 550 "/DRAM + SRAM/DDR.CKE")
			(pinfunction "R2.1")
			(pintype "passive")
		)
		(pad "3" smd roundrect
			(at 0.2 -0.298 180)
			(size 0.2 0.4)
			(layers "B.Cu" "B.Mask" "B.Paste")
			(roundrect_rratio 0.25)
			(net 541 "/DRAM + SRAM/DDR.A10")
			(pinfunction "R3.1")
			(pintype "passive")
		)
		(pad "4" smd roundrect
			(at 0.598 -0.298 180)
			(size 0.2 0.4)
			(layers "B.Cu" "B.Mask" "B.Paste")
			(roundrect_rratio 0.25)
			(net 546 "/DRAM + SRAM/DDR.A15")
			(pinfunction "R4.1")
			(pintype "passive")
		)
		(pad "5" smd roundrect
			(at 0.598 0.3 180)
			(size 0.2 0.4)
			(layers "B.Cu" "B.Mask" "B.Paste")
			(roundrect_rratio 0.25)
			(net 7 "+0V675_VTT")
			(pinfunction "R4.2")
			(pintype "passive")
		)
		(pad "6" smd roundrect
			(at 0.2 0.3 180)
			(size 0.2 0.4)
			(layers "B.Cu" "B.Mask" "B.Paste")
			(roundrect_rratio 0.25)
			(net 7 "+0V675_VTT")
			(pinfunction "R3.2")
			(pintype "passive")
		)
		(pad "7" smd roundrect
			(at -0.202 0.3 180)
			(size 0.2 0.4)
			(layers "B.Cu" "B.Mask" "B.Paste")
			(roundrect_rratio 0.25)
			(net 7 "+0V675_VTT")
			(pinfunction "R2.2")
			(pintype "passive")
		)
		(pad "8" smd roundrect
			(at -0.6 0.3 180)
			(size 0.2 0.4)
			(layers "B.Cu" "B.Mask" "B.Paste")
			(roundrect_rratio 0.25)
			(net 7 "+0V675_VTT")
			(pinfunction "R1.2")
			(pintype "passive")
		)
	)
	(footprint "antmicro-footprints:R_0402_1005Metric"
		(layer "B.Cu")
		(at 219.753 148.216 180)
		(descr "Resistor SMD 0402")
		(tags "resistor SMD 0402")
		(property "Reference" "R219"
			(at 0.753 -0.409 0)
			(layer "B.SilkS")
			(effects
				(font
					(size 0.7 0.7)
					(thickness 0.15)
				)
				(justify left bottom mirror)
			)
		)
		(property "Value" "R_10k_0402"
			(at 0 -1.4 0)
			(layer "B.Fab")
			(effects
				(font
					(size 0.7 0.7)
					(thickness 0.15)
				)
				(justify left bottom mirror)
			)
		)
		(property "Description" "SMD Chip Resistor, 10 kohm, ± 1%, 62.5 mW, 0402 [1005 Metric], Thick Film, General Purpose"
			(at 0 0 180)
			(layer "F.Fab")
			(hide yes)
			(effects
				(font
					(size 1.27 1.27)
					(thickness 0.15)
				)
			)
		)
		(property "Author" "Antmicro"
			(at 439.506 296.432 0)
			(layer "B.Fab")
			(hide yes)
			(effects
				(font
					(size 1 1)
					(thickness 0.15)
				)
				(justify mirror)
			)
		)
		(property "License" "Apache-2.0"
			(at 439.506 296.432 0)
			(layer "B.Fab")
			(hide yes)
			(effects
				(font
					(size 1 1)
					(thickness 0.15)
				)
				(justify mirror)
			)
		)
		(property "MPN" "CR0402-FX-1002GLF"
			(at 439.506 296.432 0)
			(layer "B.Fab")
			(hide yes)
			(effects
				(font
					(size 1 1)
					(thickness 0.15)
				)
				(justify mirror)
			)
		)
		(property "Manufacturer" "Bourns"
			(at 439.506 296.432 0)
			(layer "B.Fab")
			(hide yes)
			(effects
				(font
					(size 1 1)
					(thickness 0.15)
				)
				(justify mirror)
			)
		)
		(property "Tolerance" "1%"
			(at 439.506 296.432 0)
			(layer "B.Fab")
			(hide yes)
			(effects
				(font
					(size 1 1)
					(thickness 0.15)
				)
				(justify mirror)
			)
		)
		(property "Val" "10k"
			(at 439.506 296.432 0)
			(layer "B.Fab")
			(hide yes)
			(effects
				(font
					(size 1 1)
					(thickness 0.15)
				)
				(justify mirror)
			)
		)
		(sheetname "HDMI + Ethernet")
		(sheetfile "hdmi-ethernet.kicad_sch")
		(attr smd)
		(fp_rect
			(start -0.925 0.47)
			(end 0.925 -0.47)
			(stroke
				(width 0.05)
				(type default)
			)
			(fill no)
			(layer "B.CrtYd")
		)
		(fp_rect
			(start -0.5 0.25)
			(end 0.5 -0.25)
			(stroke
				(width 0.15)
				(type solid)
			)
			(fill no)
			(layer "B.Fab")
		)
		(pad "1" smd roundrect
			(at -0.48 0 180)
			(size 0.59 0.64)
			(layers "B.Cu" "B.Mask" "B.Paste")
			(roundrect_rratio 0.25)
			(net 944 "/HDMI + Ethernet/ETH_PHY_RX_DV")
			(pintype "passive")
		)
		(pad "2" smd roundrect
			(at 0.48 0 180)
			(size 0.59 0.64)
			(layers "B.Cu" "B.Mask" "B.Paste")
			(roundrect_rratio 0.25)
			(net 26 "+1V8")
			(pintype "passive")
		)
	)
	(footprint "antmicro-footprints:C_0402_1005Metric"
		(layer "B.Cu")
		(at 208.5 142 90)
		(descr "Capacitor SMD 0402")
		(tags "capacitor SMD 0402")
		(property "Reference" "C23"
			(at 1.125 1.2 270)
			(layer "B.SilkS")
			(effects
				(font
					(size 0.7 0.7)
					(thickness 0.15)
				)
				(justify left bottom mirror)
			)
		)
		(property "Value" "C_100n_0402"
			(at 0 -1.169 270)
			(layer "B.Fab")
			(effects
				(font
					(size 0.7 0.7)
					(thickness 0.15)
				)
				(justify left bottom mirror)
			)
		)
		(property "Description" "SMD Multilayer Ceramic Capacitor, 0.1 µF, 50 V, 0402 [1005 Metric], ± 10%, X5R, GRM Series"
			(at 0 0 90)
			(layer "F.Fab")
			(hide yes)
			(effects
				(font
					(size 1.27 1.27)
					(thickness 0.15)
				)
			)
		)
		(property "Author" "Antmicro"
			(at 350.5 -66.5 0)
			(layer "B.Fab")
			(hide yes)
			(effects
				(font
					(size 1 1)
					(thickness 0.15)
				)
				(justify mirror)
			)
		)
		(property "Dielectric" "X5R"
			(at 350.5 -66.5 0)
			(layer "B.Fab")
			(hide yes)
			(effects
				(font
					(size 1 1)
					(thickness 0.15)
				)
				(justify mirror)
			)
		)
		(property "License" "Apache-2.0"
			(at 350.5 -66.5 0)
			(layer "B.Fab")
			(hide yes)
			(effects
				(font
					(size 1 1)
					(thickness 0.15)
				)
				(justify mirror)
			)
		)
		(property "MPN" "GRM155R61H104KE14D"
			(at 350.5 -66.5 0)
			(layer "B.Fab")
			(hide yes)
			(effects
				(font
					(size 1 1)
					(thickness 0.15)
				)
				(justify mirror)
			)
		)
		(property "Manufacturer" "Murata"
			(at 350.5 -66.5 0)
			(layer "B.Fab")
			(hide yes)
			(effects
				(font
					(size 1 1)
					(thickness 0.15)
				)
				(justify mirror)
			)
		)
		(property "Val" "100n"
			(at 350.5 -66.5 0)
			(layer "B.Fab")
			(hide yes)
			(effects
				(font
					(size 1 1)
					(thickness 0.15)
				)
				(justify mirror)
			)
		)
		(property "Voltage" "50V"
			(at 350.5 -66.5 0)
			(layer "B.Fab")
			(hide yes)
			(effects
				(font
					(size 1 1)
					(thickness 0.15)
				)
				(justify mirror)
			)
		)
		(sheetname "FPGA Bank 12 & 13")
		(sheetfile "fpga-bank-12-13.kicad_sch")
		(attr smd)
		(fp_rect
			(start -0.925 0.47)
			(end 0.925 -0.47)
			(stroke
				(width 0.05)
				(type default)
			)
			(fill no)
			(layer "B.CrtYd")
		)
		(fp_line
			(start 0.504 -0.248)
			(end -0.494 -0.248)
			(stroke
				(width 0.15)
				(type solid)
			)
			(layer "B.Fab")
		)
		(fp_line
			(start -0.494 -0.248)
			(end -0.494 0.25)
			(stroke
				(width 0.15)
				(type solid)
			)
			(layer "B.Fab")
		)
		(fp_line
			(start 0.504 0.25)
			(end 0.504 -0.248)
			(stroke
				(width 0.15)
				(type solid)
			)
			(layer "B.Fab")
		)
		(fp_line
			(start -0.494 0.25)
			(end 0.504 0.25)
			(stroke
				(width 0.15)
				(type solid)
			)
			(layer "B.Fab")
		)
		(pad "1" smd roundrect
			(at -0.48 0 90)
			(size 0.59 0.64)
			(layers "B.Cu" "B.Mask" "B.Paste")
			(roundrect_rratio 0.25)
			(net 1 "GND")
			(pintype "passive")
		)
		(pad "2" smd roundrect
			(at 0.48 0 90)
			(size 0.59 0.64)
			(layers "B.Cu" "B.Mask" "B.Paste")
			(roundrect_rratio 0.25)
			(net 24 "+3V3")
			(pintype "passive")
		)
	)
	(footprint "antmicro-footprints:R_0402_1005Metric"
		(layer "B.Cu")
		(at 216.799999 77.899999 -90)
		(descr "Resistor SMD 0402")
		(tags "resistor SMD 0402")
		(property "Reference" "R121"
			(at -3.599999 -0.400001 90)
			(layer "B.SilkS")
			(effects
				(font
					(size 0.7 0.7)
					(thickness 0.15)
				)
				(justify left bottom mirror)
			)
		)
		(property "Value" "R_100R_0402"
			(at 0 -1.4 90)
			(layer "B.Fab")
			(effects
				(font
					(size 0.7 0.7)
					(thickness 0.15)
				)
				(justify left bottom mirror)
			)
		)
		(property "Description" "SMD Chip Resistor, 100 ohm, ± 1%, 62.5 mW, 0402 [1005 Metric], Thick Film, General Purpose"
			(at 0 0 270)
			(layer "F.Fab")
			(hide yes)
			(effects
				(font
					(size 1.27 1.27)
					(thickness 0.15)
				)
			)
		)
		(property "Author" "Antmicro"
			(at 138.9 294.699998 0)
			(layer "B.Fab")
			(hide yes)
			(effects
				(font
					(size 1 1)
					(thickness 0.15)
				)
				(justify mirror)
			)
		)
		(property "License" "Apache-2.0"
			(at 138.9 294.699998 0)
			(layer "B.Fab")
			(hide yes)
			(effects
				(font
					(size 1 1)
					(thickness 0.15)
				)
				(justify mirror)
			)
		)
		(property "MPN" "CR0402-FX-1000GLF"
			(at 138.9 294.699998 0)
			(layer "B.Fab")
			(hide yes)
			(effects
				(font
					(size 1 1)
					(thickness 0.15)
				)
				(justify mirror)
			)
		)
		(property "Manufacturer" "Bourns"
			(at 138.9 294.699998 0)
			(layer "B.Fab")
			(hide yes)
			(effects
				(font
					(size 1 1)
					(thickness 0.15)
				)
				(justify mirror)
			)
		)
		(property "Tolerance" "1%"
			(at 138.9 294.699998 0)
			(layer "B.Fab")
			(hide yes)
			(effects
				(font
					(size 1 1)
					(thickness 0.15)
				)
				(justify mirror)
			)
		)
		(property "Val" "100R"
			(at 138.9 294.699998 0)
			(layer "B.Fab")
			(hide yes)
			(effects
				(font
					(size 1 1)
					(thickness 0.15)
				)
				(justify mirror)
			)
		)
		(sheetname "User GPIO + LED + button + DIP switch")
		(sheetfile "user-gpio.kicad_sch")
		(attr smd)
		(fp_rect
			(start -0.925 0.47)
			(end 0.925 -0.47)
			(stroke
				(width 0.05)
				(type default)
			)
			(fill no)
			(layer "B.CrtYd")
		)
		(fp_rect
			(start -0.5 0.25)
			(end 0.5 -0.25)
			(stroke
				(width 0.15)
				(type solid)
			)
			(fill no)
			(layer "B.Fab")
		)
		(pad "1" smd roundrect
			(at -0.48 0 270)
			(size 0.59 0.64)
			(layers "B.Cu" "B.Mask" "B.Paste")
			(roundrect_rratio 0.25)
			(net 457 "/FPGA Bank 12 & 13/PMOD_A.IO2")
			(pintype "passive")
		)
		(pad "2" smd roundrect
			(at 0.48 0 270)
			(size 0.59 0.64)
			(layers "B.Cu" "B.Mask" "B.Paste")
			(roundrect_rratio 0.25)
			(net 807 "/User GPIO + LED + button + DIP switch/PMOD_A_2")
			(pintype "passive")
		)
	)
	(footprint "antmicro-footprints:C_0603_1608Metric"
		(layer "B.Cu")
		(at 192.19 136.14 180)
		(descr "Capacitor SMD 0603")
		(tags "capacitor 0603")
		(property "Reference" "C108"
			(at -23.375 28.075 0)
			(layer "B.SilkS")
			(effects
				(font
					(size 0.7 0.7)
					(thickness 0.15)
				)
				(justify left bottom mirror)
			)
		)
		(property "Value" "C_47u_0603"
			(at 0 -1.6 0)
			(layer "B.Fab")
			(effects
				(font
					(size 0.7 0.7)
					(thickness 0.15)
				)
				(justify left bottom mirror)
			)
		)
		(property "Description" "SMD Multilayer Ceramic Capacitor, 47 µF, 6.3 V, 0603 [1608 Metric], ± 20%, X5R, GRM Series"
			(at 0 0 180)
			(layer "F.Fab")
			(hide yes)
			(effects
				(font
					(size 1.27 1.27)
					(thickness 0.15)
				)
			)
		)
		(property "Author" "Antmicro"
			(at 384.38 272.28 0)
			(layer "B.Fab")
			(hide yes)
			(effects
				(font
					(size 1 1)
					(thickness 0.15)
				)
				(justify mirror)
			)
		)
		(property "Dielectric" ""
			(at 384.38 272.28 0)
			(layer "B.Fab")
			(hide yes)
			(effects
				(font
					(size 1 1)
					(thickness 0.15)
				)
				(justify mirror)
			)
		)
		(property "License" "Apache-2.0"
			(at 384.38 272.28 0)
			(layer "B.Fab")
			(hide yes)
			(effects
				(font
					(size 1 1)
					(thickness 0.15)
				)
				(justify mirror)
			)
		)
		(property "MPN" "GRM188R60J476ME15D"
			(at 384.38 272.28 0)
			(layer "B.Fab")
			(hide yes)
			(effects
				(font
					(size 1 1)
					(thickness 0.15)
				)
				(justify mirror)
			)
		)
		(property "Manufacturer" "Murata"
			(at 384.38 272.28 0)
			(layer "B.Fab")
			(hide yes)
			(effects
				(font
					(size 1 1)
					(thickness 0.15)
				)
				(justify mirror)
			)
		)
		(property "Val" "47u"
			(at 384.38 272.28 0)
			(layer "B.Fab")
			(hide yes)
			(effects
				(font
					(size 1 1)
					(thickness 0.15)
				)
				(justify mirror)
			)
		)
		(property "Voltage" ""
			(at 384.38 272.28 0)
			(layer "B.Fab")
			(hide yes)
			(effects
				(font
					(size 1 1)
					(thickness 0.15)
				)
				(justify mirror)
			)
		)
		(sheetname "FPGA Bank 33 & 34")
		(sheetfile "fpga-bank-33-34.kicad_sch")
		(attr smd)
		(fp_line
			(start -0.15 0.4)
			(end 0.15 0.4)
			(stroke
				(width 0.15)
				(type solid)
			)
			(layer "B.SilkS")
		)
		(fp_line
			(start -0.15 -0.4)
			(end 0.15 -0.4)
			(stroke
				(width 0.15)
				(type solid)
			)
			(layer "B.SilkS")
		)
		(fp_rect
			(start -1.25 0.65)
			(end 1.25 -0.65)
			(stroke
				(width 0.05)
				(type solid)
			)
			(fill no)
			(layer "B.CrtYd")
		)
		(fp_rect
			(start -0.8 0.4)
			(end 0.8 -0.4)
			(stroke
				(width 0.15)
				(type solid)
			)
			(fill no)
			(layer "B.Fab")
		)
		(pad "1" smd roundrect
			(at -0.7 0 180)
			(size 0.8 1)
			(layers "B.Cu" "B.Mask" "B.Paste")
			(roundrect_rratio 0.2)
			(net 26 "+1V8")
			(pintype "passive")
		)
		(pad "2" smd roundrect
			(at 0.7 0 180)
			(size 0.8 1)
			(layers "B.Cu" "B.Mask" "B.Paste")
			(roundrect_rratio 0.2)
			(net 1 "GND")
			(pintype "passive")
		)
	)
)
